(kicad_pcb
	(version 20241229)
	(generator "pcbnew")
	(generator_version "9.0")
	(general
		(thickness 1.61)
		(legacy_teardrops no)
	)
	(paper "A3")
	(title_block
		(title "RDIMM DDR5 Tester")
		(date "2026-05-21")
		(rev "2.2.0")
		(company "Antmicro")
		(comment 9 "footprints 580-584 of 796")
	)
	(layers
		(0 "F.Cu" signal)
		(4 "In1.Cu" power)
		(6 "In2.Cu" mixed)
		(8 "In3.Cu" power)
		(10 "In4.Cu" mixed)
		(12 "In5.Cu" power)
		(14 "In6.Cu" mixed)
		(16 "In7.Cu" power)
		(18 "In8.Cu" power)
		(20 "In9.Cu" mixed)
		(22 "In10.Cu" power)
		(2 "B.Cu" signal)
		(9 "F.Adhes" user "F.Adhesive")
		(11 "B.Adhes" user "B.Adhesive")
		(13 "F.Paste" user)
		(15 "B.Paste" user)
		(5 "F.SilkS" user "F.Silkscreen")
		(7 "B.SilkS" user "B.Silkscreen")
		(1 "F.Mask" user)
		(3 "B.Mask" user)
		(17 "Dwgs.User" user "User.Drawings")
		(19 "Cmts.User" user "User.Comments")
		(21 "Eco1.User" user "User.Eco1")
		(23 "Eco2.User" user "User.Eco2")
		(25 "Edge.Cuts" user)
		(27 "Margin" user)
		(31 "F.CrtYd" user "F.Courtyard")
		(29 "B.CrtYd" user "B.Courtyard")
		(35 "F.Fab" user)
		(33 "B.Fab" user)
	)
	(footprint "antmicro-footprints:C_0402_1005Metric_EIA"
		(layer "B.Cu")
		(at 178.499999 157)
		(descr "Capacitor SMD 0402 (1005 Metric), square (rectangular) end terminal, IPC_7351 nominal, (Body size source: IPC-SM-782 page 76, https://www.pcb-3d.com/wordpress/wp-content/uploads/ipc-sm-782a_amendment_1_and_2.pdf)")
		(tags "capacitor 0402")
		(property "Reference" "C17"
			(at -2.999999 0.45 0)
			(layer "B.SilkS")
			(effects
				(font
					(size 0.7 0.7)
					(thickness 0.15)
				)
				(justify right bottom mirror)
			)
		)
		(property "Value" "C_100n_0402"
			(at 0 -1.169 0)
			(layer "B.Fab")
			(effects
				(font
					(size 0.7 0.7)
					(thickness 0.15)
				)
				(justify right bottom mirror)
			)
		)
		(property "Datasheet" "https://www.murata.com/products/productdetail?partno=GRM155R61H104KE14%23"
			(at 0 0 0)
			(layer "F.Fab")
			(hide yes)
			(effects
				(font
					(size 1.27 1.27)
					(thickness 0.15)
				)
			)
		)
		(property "MPN" "GRM155R61H104KE14D"
			(at 0 0 0)
			(unlocked yes)
			(layer "B.Fab")
			(hide yes)
			(effects
				(font
					(size 1 1)
					(thickness 0.15)
				)
				(justify mirror)
			)
		)
		(property "Manufacturer" "Murata"
			(at 0 0 0)
			(unlocked yes)
			(layer "B.Fab")
			(hide yes)
			(effects
				(font
					(size 1 1)
					(thickness 0.15)
				)
				(justify mirror)
			)
		)
		(property "License" "Apache-2.0"
			(at 0 0 0)
			(unlocked yes)
			(layer "B.Fab")
			(hide yes)
			(effects
				(font
					(size 1 1)
					(thickness 0.15)
				)
				(justify mirror)
			)
		)
		(property "Author" "Antmicro"
			(at 0 0 0)
			(unlocked yes)
			(layer "B.Fab")
			(hide yes)
			(effects
				(font
					(size 1 1)
					(thickness 0.15)
				)
				(justify mirror)
			)
		)
		(property "Val" "100n"
			(at 0 0 0)
			(unlocked yes)
			(layer "B.Fab")
			(hide yes)
			(effects
				(font
					(size 1 1)
					(thickness 0.15)
				)
				(justify mirror)
			)
		)
		(property "Voltage" "50V"
			(at 0 0 0)
			(unlocked yes)
			(layer "B.Fab")
			(hide yes)
			(effects
				(font
					(size 1 1)
					(thickness 0.15)
				)
				(justify mirror)
			)
		)
		(property "Dielectric" "X5R"
			(at 0 0 0)
			(unlocked yes)
			(layer "B.Fab")
			(hide yes)
			(effects
				(font
					(size 1 1)
					(thickness 0.15)
				)
				(justify mirror)
			)
		)
		(sheetname "/FPGA power/")
		(sheetfile "fpga-power.kicad_sch")
		(attr smd)
		(fp_rect
			(start -0.95 0.45)
			(end 0.95 -0.45)
			(stroke
				(width 0.05)
				(type default)
			)
			(fill no)
			(layer "B.CrtYd")
		)
		(fp_line
			(start -0.5 -0.248)
			(end -0.5 0.25)
			(stroke
				(width 0.15)
				(type solid)
			)
			(layer "B.Fab")
		)
		(fp_line
			(start -0.5 0.25)
			(end 0.498 0.25)
			(stroke
				(width 0.15)
				(type solid)
			)
			(layer "B.Fab")
		)
		(fp_line
			(start 0.498 -0.248)
			(end -0.5 -0.248)
			(stroke
				(width 0.15)
				(type solid)
			)
			(layer "B.Fab")
		)
		(fp_line
			(start 0.498 0.25)
			(end 0.498 -0.248)
			(stroke
				(width 0.15)
				(type solid)
			)
			(layer "B.Fab")
		)
		(fp_text user "License: Apache-2.0"
			(at -0.9656 -4.369 180)
			(layer "B.Fab")
			(effects
				(font
					(size 0.7 0.7)
					(thickness 0.15)
				)
				(justify left bottom mirror)
			)
		)
		(fp_text user "Author: Antmicro"
			(at -0.9656 -5.569 180)
			(layer "B.Fab")
			(effects
				(font
					(size 0.7 0.7)
					(thickness 0.15)
				)
				(justify left bottom mirror)
			)
		)
		(fp_text user "${REFERENCE}"
			(at -0.9656 -3.169 180)
			(layer "B.Fab")
			(effects
				(font
					(size 0.7 0.7)
					(thickness 0.15)
				)
				(justify left bottom mirror)
			)
		)
		(pad "1" smd roundrect
			(at -0.5 0 270)
			(size 0.6 0.6)
			(layers "B.Cu" "B.Mask" "B.Paste")
			(roundrect_rratio 0.25)
			(net 1 "GND")
			(pintype "passive")
		)
		(pad "2" smd roundrect
			(at 0.498 0)
			(size 0.6 0.6)
			(layers "B.Cu" "B.Mask" "B.Paste")
			(roundrect_rratio 0.25)
			(net 151 "+3V3")
			(pintype "passive")
		)
	)
	(footprint "antmicro-footprints:C_0603_1608Metric"
		(layer "B.Cu")
		(at 246.94 121.47 90)
		(descr "Capacitor SMD 0603")
		(tags "capacitor 0603")
		(property "Reference" "C327"
			(at -4.11 0.48 90)
			(layer "B.SilkS")
			(effects
				(font
					(size 0.7 0.7)
					(thickness 0.15)
				)
				(justify right bottom mirror)
			)
		)
		(property "Value" "C_10u_25V_0603"
			(at -1.42757 -1.770288 90)
			(layer "B.Fab")
			(effects
				(font
					(size 0.7 0.7)
					(thickness 0.15)
				)
				(justify right bottom mirror)
			)
		)
		(property "Datasheet" "https://product.tdk.com/en/search/capacitor/ceramic/mlcc/info?part_no=C1608X5R1E106M080AC"
			(at 0 0 90)
			(layer "F.Fab")
			(hide yes)
			(effects
				(font
					(size 1.27 1.27)
					(thickness 0.15)
				)
			)
		)
		(property "MPN" "C1608X5R1E106M080AC"
			(at 0 0 90)
			(unlocked yes)
			(layer "B.Fab")
			(hide yes)
			(effects
				(font
					(size 1 1)
					(thickness 0.15)
				)
				(justify mirror)
			)
		)
		(property "Manufacturer" "TDK"
			(at 0 0 90)
			(unlocked yes)
			(layer "B.Fab")
			(hide yes)
			(effects
				(font
					(size 1 1)
					(thickness 0.15)
				)
				(justify mirror)
			)
		)
		(property "License" "Apache-2.0"
			(at 0 0 90)
			(unlocked yes)
			(layer "B.Fab")
			(hide yes)
			(effects
				(font
					(size 1 1)
					(thickness 0.15)
				)
				(justify mirror)
			)
		)
		(property "Author" "Antmicro"
			(at 0 0 90)
			(unlocked yes)
			(layer "B.Fab")
			(hide yes)
			(effects
				(font
					(size 1 1)
					(thickness 0.15)
				)
				(justify mirror)
			)
		)
		(property "Val" "10u"
			(at 0 0 90)
			(unlocked yes)
			(layer "B.Fab")
			(hide yes)
			(effects
				(font
					(size 1 1)
					(thickness 0.15)
				)
				(justify mirror)
			)
		)
		(property "Voltage" "25V"
			(at 0 0 90)
			(unlocked yes)
			(layer "B.Fab")
			(hide yes)
			(effects
				(font
					(size 1 1)
					(thickness 0.15)
				)
				(justify mirror)
			)
		)
		(property "Dielectric" ""
			(at 0 0 90)
			(unlocked yes)
			(layer "B.Fab")
			(hide yes)
			(effects
				(font
					(size 1 1)
					(thickness 0.15)
				)
				(justify mirror)
			)
		)
		(sheetname "/Supply/")
		(sheetfile "supply.kicad_sch")
		(attr smd)
		(fp_line
			(start -0.15 -0.4)
			(end 0.15 -0.4)
			(stroke
				(width 0.15)
				(type solid)
			)
			(layer "B.SilkS")
		)
		(fp_line
			(start -0.15 0.4)
			(end 0.15 0.4)
			(stroke
				(width 0.15)
				(type solid)
			)
			(layer "B.SilkS")
		)
		(fp_rect
			(start -1.25 0.65)
			(end 1.25 -0.65)
			(stroke
				(width 0.05)
				(type solid)
			)
			(fill no)
			(layer "B.CrtYd")
		)
		(fp_rect
			(start -0.8 0.4)
			(end 0.8 -0.4)
			(stroke
				(width 0.15)
				(type solid)
			)
			(fill no)
			(layer "B.Fab")
		)
		(fp_text user "${REFERENCE}"
			(at -1.682 -3.895 270)
			(layer "B.Fab")
			(effects
				(font
					(size 0.7 0.7)
					(thickness 0.15)
				)
				(justify left bottom mirror)
			)
		)
		(fp_text user "Author: Antmicro"
			(at -1.682 -4.894 270)
			(layer "B.Fab")
			(effects
				(font
					(size 0.7 0.7)
					(thickness 0.15)
				)
				(justify left bottom mirror)
			)
		)
		(fp_text user "License: Apache-2.0"
			(at -1.682 -5.895 270)
			(layer "B.Fab")
			(effects
				(font
					(size 0.7 0.7)
					(thickness 0.15)
				)
				(justify left bottom mirror)
			)
		)
		(pad "1" smd roundrect
			(at -0.7 0 90)
			(size 0.8 1)
			(layers "B.Cu" "B.Mask" "B.Paste")
			(roundrect_rratio 0.2)
			(net 1 "GND")
			(pintype "passive")
		)
		(pad "2" smd roundrect
			(at 0.7 0 90)
			(size 0.8 1)
			(layers "B.Cu" "B.Mask" "B.Paste")
			(roundrect_rratio 0.2)
			(net 35 "VDC")
			(pintype "passive")
		)
	)
	(footprint "antmicro-footprints:R_0402_1005Metric"
		(layer "B.Cu")
		(at 260.499499 153.299 90)
		(descr "Resistor SMD 0402")
		(tags "resistor SMD 0402")
		(property "Reference" "R167"
			(at 0.949 0.400501 90)
			(layer "B.SilkS")
			(effects
				(font
					(size 0.7 0.7)
					(thickness 0.15)
				)
				(justify right bottom mirror)
			)
		)
		(property "Value" "R_0R_0402"
			(at -1.011843 -1.772047 90)
			(layer "B.Fab")
			(effects
				(font
					(size 0.7 0.7)
					(thickness 0.15)
				)
				(justify right bottom mirror)
			)
		)
		(property "Datasheet" "https://industrial.panasonic.com/cdbs/www-data/pdf/RDA0000/AOA0000C301.pdf"
			(at 0 0 90)
			(layer "F.Fab")
			(hide yes)
			(effects
				(font
					(size 1.27 1.27)
					(thickness 0.15)
				)
			)
		)
		(property "Manufacturer" "Panasonic"
			(at 0 0 90)
			(unlocked yes)
			(layer "B.Fab")
			(hide yes)
			(effects
				(font
					(size 1 1)
					(thickness 0.15)
				)
				(justify mirror)
			)
		)
		(property "MPN" "ERJ2GE0R00X"
			(at 0 0 90)
			(unlocked yes)
			(layer "B.Fab")
			(hide yes)
			(effects
				(font
					(size 1 1)
					(thickness 0.15)
				)
				(justify mirror)
			)
		)
		(property "Val" "0R"
			(at 0 0 90)
			(unlocked yes)
			(layer "B.Fab")
			(hide yes)
			(effects
				(font
					(size 1 1)
					(thickness 0.15)
				)
				(justify mirror)
			)
		)
		(property "License" "Apache-2.0"
			(at 0 0 90)
			(unlocked yes)
			(layer "B.Fab")
			(hide yes)
			(effects
				(font
					(size 1 1)
					(thickness 0.15)
				)
				(justify mirror)
			)
		)
		(property "Author" "Antmicro"
			(at 0 0 90)
			(unlocked yes)
			(layer "B.Fab")
			(hide yes)
			(effects
				(font
					(size 1 1)
					(thickness 0.15)
				)
				(justify mirror)
			)
		)
		(property "Tolerance" "~"
			(at 0 0 90)
			(unlocked yes)
			(layer "B.Fab")
			(hide yes)
			(effects
				(font
					(size 1 1)
					(thickness 0.15)
				)
				(justify mirror)
			)
		)
		(property "Current" "1A"
			(at 0 0 90)
			(unlocked yes)
			(layer "B.Fab")
			(hide yes)
			(effects
				(font
					(size 1 1)
					(thickness 0.15)
				)
				(justify mirror)
			)
		)
		(sheetname "/Supply/DC-DC IO/")
		(sheetfile "dc-dc-io.kicad_sch")
		(attr smd exclude_from_bom dnp)
		(fp_rect
			(start -0.925 0.47)
			(end 0.925 -0.47)
			(stroke
				(width 0.05)
				(type default)
			)
			(fill no)
			(layer "B.CrtYd")
		)
		(fp_rect
			(start -0.5 0.25)
			(end 0.5 -0.25)
			(stroke
				(width 0.15)
				(type solid)
			)
			(fill no)
			(layer "B.Fab")
		)
		(fp_text user "Author: Antmicro"
			(at -0.95 -4.169 270)
			(layer "B.Fab")
			(effects
				(font
					(size 0.7 0.7)
					(thickness 0.15)
				)
				(justify left bottom mirror)
			)
		)
		(fp_text user "License: Apache-2.0"
			(at -0.95 -5.169 270)
			(layer "B.Fab")
			(effects
				(font
					(size 0.7 0.7)
					(thickness 0.15)
				)
				(justify left bottom mirror)
			)
		)
		(fp_text user "${REFERENCE}"
			(at -0.95 -3.168 270)
			(layer "B.Fab")
			(effects
				(font
					(size 0.7 0.7)
					(thickness 0.15)
				)
				(justify left bottom mirror)
			)
		)
		(pad "1" smd roundrect
			(at -0.48 0 90)
			(size 0.59 0.64)
			(layers "B.Cu" "B.Mask" "B.Paste")
			(roundrect_rratio 0.25)
			(net 1 "GND")
			(pintype "passive")
		)
		(pad "2" smd roundrect
			(at 0.48 0 90)
			(size 0.59 0.64)
			(layers "B.Cu" "B.Mask" "B.Paste")
			(roundrect_rratio 0.25)
			(net 718 "/Supply/DC-DC IO/FB7")
			(pintype "passive")
		)
	)
	(footprint "antmicro-footprints:C_0402_1005Metric"
		(layer "B.Cu")
		(at 122.95 154.61 180)
		(descr "Capacitor SMD 0402")
		(tags "capacitor SMD 0402")
		(property "Reference" "C291"
			(at -5.22 -1.66 0)
			(layer "B.SilkS")
			(effects
				(font
					(size 0.7 0.7)
					(thickness 0.15)
				)
				(justify left bottom mirror)
			)
		)
		(property "Value" "C_100n_0402"
			(at -1.022927 -2.155213 0)
			(layer "B.Fab")
			(effects
				(font
					(size 0.7 0.7)
					(thickness 0.15)
				)
				(justify left bottom mirror)
			)
		)
		(property "Datasheet" "https://www.murata.com/products/productdetail?partno=GRM155R61H104KE14%23"
			(at 0 0 180)
			(layer "F.Fab")
			(hide yes)
			(effects
				(font
					(size 1.27 1.27)
					(thickness 0.15)
				)
			)
		)
		(property "Manufacturer" "Murata"
			(at 0 0 180)
			(unlocked yes)
			(layer "B.Fab")
			(hide yes)
			(effects
				(font
					(size 1 1)
					(thickness 0.15)
				)
				(justify mirror)
			)
		)
		(property "MPN" "GRM155R61H104KE14D"
			(at 0 0 180)
			(unlocked yes)
			(layer "B.Fab")
			(hide yes)
			(effects
				(font
					(size 1 1)
					(thickness 0.15)
				)
				(justify mirror)
			)
		)
		(property "Val" "100n"
			(at 0 0 180)
			(unlocked yes)
			(layer "B.Fab")
			(hide yes)
			(effects
				(font
					(size 1 1)
					(thickness 0.15)
				)
				(justify mirror)
			)
		)
		(property "License" "Apache-2.0"
			(at 0 0 180)
			(unlocked yes)
			(layer "B.Fab")
			(hide yes)
			(effects
				(font
					(size 1 1)
					(thickness 0.15)
				)
				(justify mirror)
			)
		)
		(property "Author" "Antmicro"
			(at 0 0 180)
			(unlocked yes)
			(layer "B.Fab")
			(hide yes)
			(effects
				(font
					(size 1 1)
					(thickness 0.15)
				)
				(justify mirror)
			)
		)
		(property "Voltage" "50V"
			(at 0 0 180)
			(unlocked yes)
			(layer "B.Fab")
			(hide yes)
			(effects
				(font
					(size 1 1)
					(thickness 0.15)
				)
				(justify mirror)
			)
		)
		(property "Dielectric" "X5R"
			(at 0 0 180)
			(unlocked yes)
			(layer "B.Fab")
			(hide yes)
			(effects
				(font
					(size 1 1)
					(thickness 0.15)
				)
				(justify mirror)
			)
		)
		(sheetname "/FPGA MGT Interface/")
		(sheetfile "fpga-mgt.kicad_sch")
		(attr smd)
		(fp_rect
			(start -0.925 0.47)
			(end 0.925 -0.47)
			(stroke
				(width 0.05)
				(type default)
			)
			(fill no)
			(layer "B.CrtYd")
		)
		(fp_line
			(start 0.504 0.25)
			(end 0.504 -0.248)
			(stroke
				(width 0.15)
				(type solid)
			)
			(layer "B.Fab")
		)
		(fp_line
			(start 0.504 -0.248)
			(end -0.494 -0.248)
			(stroke
				(width 0.15)
				(type solid)
			)
			(layer "B.Fab")
		)
		(fp_line
			(start -0.494 0.25)
			(end 0.504 0.25)
			(stroke
				(width 0.15)
				(type solid)
			)
			(layer "B.Fab")
		)
		(fp_line
			(start -0.494 -0.248)
			(end -0.494 0.25)
			(stroke
				(width 0.15)
				(type solid)
			)
			(layer "B.Fab")
		)
		(fp_text user "${REFERENCE}"
			(at -0.939 -4.599 0)
			(layer "B.Fab")
			(effects
				(font
					(size 0.7 0.7)
					(thickness 0.15)
				)
				(justify left bottom mirror)
			)
		)
		(fp_text user "Author: Antmicro"
			(at -0.939 -3.399 0)
			(layer "B.Fab")
			(effects
				(font
					(size 0.7 0.7)
					(thickness 0.15)
				)
				(justify left bottom mirror)
			)
		)
		(fp_text user "License: Apache-2.0"
			(at -0.939 -5.799 0)
			(layer "B.Fab")
			(effects
				(font
					(size 0.7 0.7)
					(thickness 0.15)
				)
				(justify left bottom mirror)
			)
		)
		(pad "1" smd roundrect
			(at -0.48 0 180)
			(size 0.59 0.64)
			(layers "B.Cu" "B.Mask" "B.Paste")
			(roundrect_rratio 0.25)
			(net 291 "/FPGA MGT Interface/HDMI_IN_CLK_C_N")
			(pintype "passive")
		)
		(pad "2" smd roundrect
			(at 0.48 0 180)
			(size 0.59 0.64)
			(layers "B.Cu" "B.Mask" "B.Paste")
			(roundrect_rratio 0.25)
			(net 292 "/FPGA MGT Interface/HDMI_IN.CLK_N")
			(pintype "passive")
		)
	)
	(footprint "antmicro-footprints:R_0402_1005Metric"
		(layer "B.Cu")
		(at 255.289499 138.25 180)
		(descr "Resistor SMD 0402")
		(tags "resistor SMD 0402")
		(property "Reference" "R206"
			(at -4.210501 -0.35 0)
			(layer "B.SilkS")
			(effects
				(font
					(size 0.7 0.7)
					(thickness 0.15)
				)
				(justify left bottom mirror)
			)
		)
		(property "Value" "R_4k7_0402"
			(at -1.011843 -1.772047 0)
			(layer "B.Fab")
			(effects
				(font
					(size 0.7 0.7)
					(thickness 0.15)
				)
				(justify left bottom mirror)
			)
		)
		(property "Datasheet" "https://www.bourns.com/docs/product-datasheets/cr.pdf"
			(at 0 0 180)
			(layer "F.Fab")
			(hide yes)
			(effects
				(font
					(size 1.27 1.27)
					(thickness 0.15)
				)
			)
		)
		(property "MPN" "CR0402-FX-4701GLF"
			(at 0 0 180)
			(unlocked yes)
			(layer "B.Fab")
			(hide yes)
			(effects
				(font
					(size 1 1)
					(thickness 0.15)
				)
				(justify mirror)
			)
		)
		(property "Manufacturer" "Bourns"
			(at 0 0 180)
			(unlocked yes)
			(layer "B.Fab")
			(hide yes)
			(effects
				(font
					(size 1 1)
					(thickness 0.15)
				)
				(justify mirror)
			)
		)
		(property "License" "Apache-2.0"
			(at 0 0 180)
			(unlocked yes)
			(layer "B.Fab")
			(hide yes)
			(effects
				(font
					(size 1 1)
					(thickness 0.15)
				)
				(justify mirror)
			)
		)
		(property "Author" "Antmicro"
			(at 0 0 180)
			(unlocked yes)
			(layer "B.Fab")
			(hide yes)
			(effects
				(font
					(size 1 1)
					(thickness 0.15)
				)
				(justify mirror)
			)
		)
		(property "Val" "4k7"
			(at 0 0 180)
			(unlocked yes)
			(layer "B.Fab")
			(hide yes)
			(effects
				(font
					(size 1 1)
					(thickness 0.15)
				)
				(justify mirror)
			)
		)
		(property "Tolerance" "1%"
			(at 0 0 180)
			(unlocked yes)
			(layer "B.Fab")
			(hide yes)
			(effects
				(font
					(size 1 1)
					(thickness 0.15)
				)
				(justify mirror)
			)
		)
		(sheetname "/Supply/")
		(sheetfile "supply.kicad_sch")
		(attr smd)
		(fp_rect
			(start -0.925 0.47)
			(end 0.925 -0.47)
			(stroke
				(width 0.05)
				(type default)
			)
			(fill no)
			(layer "B.CrtYd")
		)
		(fp_rect
			(start -0.5 0.25)
			(end 0.5 -0.25)
			(stroke
				(width 0.15)
				(type solid)
			)
			(fill no)
			(layer "B.Fab")
		)
		(fp_text user "License: Apache-2.0"
			(at -0.95 -5.169 0)
			(layer "B.Fab")
			(effects
				(font
					(size 0.7 0.7)
					(thickness 0.15)
				)
				(justify left bottom mirror)
			)
		)
		(fp_text user "Author: Antmicro"
			(at -0.95 -4.169 0)
			(layer "B.Fab")
			(effects
				(font
					(size 0.7 0.7)
					(thickness 0.15)
				)
				(justify left bottom mirror)
			)
		)
		(fp_text user "${REFERENCE}"
			(at -0.95 -3.168 0)
			(layer "B.Fab")
			(effects
				(font
					(size 0.7 0.7)
					(thickness 0.15)
				)
				(justify left bottom mirror)
			)
		)
		(pad "1" smd roundrect
			(at -0.48 0 180)
			(size 0.59 0.64)
			(layers "B.Cu" "B.Mask" "B.Paste")
			(roundrect_rratio 0.25)
			(net 625 "Net-(Q17-D)")
			(pintype "passive")
		)
		(pad "2" smd roundrect
			(at 0.48 0 180)
			(size 0.59 0.64)
			(layers "B.Cu" "B.Mask" "B.Paste")
			(roundrect_rratio 0.25)
			(net 50 "/Supply/SEQ_EN")
			(pintype "passive")
		)
	)
)
